(kicad_pcb
	(version 20241229)
	(generator "pcbnew")
	(generator_version "9.0")
	(general
		(thickness 1.599998)
		(legacy_teardrops no)
	)
	(paper "A4")
	(title_block
		(title "Artix - Datacenter Secure Control Module (DC-SCM)")
		(date "2024-11-06")
		(rev "1.1.3")
		(comment 9 "footprints 502-506 of 544")
	)
	(layers
		(0 "F.Cu" signal)
		(4 "In1.Cu" signal)
		(6 "In2.Cu" signal)
		(8 "In3.Cu" signal)
		(10 "In4.Cu" signal)
		(12 "In5.Cu" signal)
		(14 "In6.Cu" signal)
		(2 "B.Cu" signal)
		(9 "F.Adhes" user "F.Adhesive")
		(11 "B.Adhes" user "B.Adhesive")
		(13 "F.Paste" user)
		(15 "B.Paste" user)
		(5 "F.SilkS" user "F.Silkscreen")
		(7 "B.SilkS" user "B.Silkscreen")
		(1 "F.Mask" user)
		(3 "B.Mask" user)
		(17 "Dwgs.User" user "User.Drawings")
		(19 "Cmts.User" user "User.Comments")
		(21 "Eco1.User" user "User.Eco1")
		(23 "Eco2.User" user "User.Eco2")
		(25 "Edge.Cuts" user)
		(27 "Margin" user)
		(31 "F.CrtYd" user "F.Courtyard")
		(29 "B.CrtYd" user "B.Courtyard")
		(35 "F.Fab" user)
		(33 "B.Fab" user)
	)
	(footprint "antmicro-footprints:R_0402_1005Metric"
		(layer "B.Cu")
		(at 93.965 91.065 -90)
		(descr "Resistor SMD 0402")
		(tags "resistor SMD 0402")
		(property "Reference" "R165"
			(at -3.965 0.365 90)
			(layer "B.SilkS")
			(effects
				(font
					(size 0.7 0.7)
					(thickness 0.15)
				)
				(justify left bottom mirror)
			)
		)
		(property "Value" "R_220R_0402"
			(at 0 -1.4 90)
			(layer "B.Fab")
			(effects
				(font
					(size 0.7 0.7)
					(thickness 0.15)
				)
				(justify left bottom mirror)
			)
		)
		(property "Datasheet" "https://www.bourns.com/docs/product-datasheets/cr.pdf"
			(at 0 0 270)
			(layer "F.Fab")
			(hide yes)
			(effects
				(font
					(size 1.27 1.27)
					(thickness 0.15)
				)
			)
		)
		(property "Description" "SMD Chip Resistor, 220 ohm, ± 1%, 62.5 mW, 0402 [1005 Metric], Thick Film, General Purpose"
			(at 0 0 270)
			(layer "F.Fab")
			(hide yes)
			(effects
				(font
					(size 1.27 1.27)
					(thickness 0.15)
				)
			)
		)
		(property "Author" "Antmicro"
			(at 2.9 185.03 0)
			(layer "B.Fab")
			(hide yes)
			(effects
				(font
					(size 1 1)
					(thickness 0.15)
				)
				(justify mirror)
			)
		)
		(property "License" "Apache-2.0"
			(at 2.9 185.03 0)
			(layer "B.Fab")
			(hide yes)
			(effects
				(font
					(size 1 1)
					(thickness 0.15)
				)
				(justify mirror)
			)
		)
		(property "MPN" "CR0402-FX-2200GLF"
			(at 2.9 185.03 0)
			(layer "B.Fab")
			(hide yes)
			(effects
				(font
					(size 1 1)
					(thickness 0.15)
				)
				(justify mirror)
			)
		)
		(property "Manufacturer" "Bourns"
			(at 2.9 185.03 0)
			(layer "B.Fab")
			(hide yes)
			(effects
				(font
					(size 1 1)
					(thickness 0.15)
				)
				(justify mirror)
			)
		)
		(property "Tolerance" "1%"
			(at 2.9 185.03 0)
			(layer "B.Fab")
			(hide yes)
			(effects
				(font
					(size 1 1)
					(thickness 0.15)
				)
				(justify mirror)
			)
		)
		(property "Val" "220R"
			(at 2.9 185.03 0)
			(layer "B.Fab")
			(hide yes)
			(effects
				(font
					(size 1 1)
					(thickness 0.15)
				)
				(justify mirror)
			)
		)
		(sheetname "/Ethernet/")
		(sheetfile "ethernet.kicad_sch")
		(attr smd)
		(fp_rect
			(start -0.925 0.47)
			(end 0.925 -0.47)
			(stroke
				(width 0.05)
				(type default)
			)
			(fill no)
			(layer "B.CrtYd")
		)
		(fp_rect
			(start -0.5 0.25)
			(end 0.5 -0.25)
			(stroke
				(width 0.15)
				(type solid)
			)
			(fill no)
			(layer "B.Fab")
		)
		(pad "1" smd roundrect
			(at -0.48 0 270)
			(size 0.59 0.64)
			(layers "B.Cu" "B.Mask" "B.Paste")
			(roundrect_rratio 0.25)
			(net 575 "Net-(J1-Pad13)")
			(pintype "passive")
		)
		(pad "2" smd roundrect
			(at 0.48 0 270)
			(size 0.59 0.64)
			(layers "B.Cu" "B.Mask" "B.Paste")
			(roundrect_rratio 0.25)
			(net 415 "/Ethernet/ETH_LED1")
			(pintype "passive")
		)
	)
	(footprint "antmicro-footprints:C_0402_1005Metric"
		(layer "B.Cu")
		(at 91.775 124.375)
		(descr "Capacitor SMD 0402")
		(tags "capacitor SMD 0402")
		(property "Reference" "C241"
			(at -3.775 0.325 0)
			(layer "B.SilkS")
			(effects
				(font
					(size 0.7 0.7)
					(thickness 0.15)
				)
				(justify right bottom mirror)
			)
		)
		(property "Value" "C_100n_6V3_0402"
			(at 0 -1.4 0)
			(layer "B.Fab")
			(effects
				(font
					(size 0.7 0.7)
					(thickness 0.15)
				)
				(justify right bottom mirror)
			)
		)
		(property "Datasheet" "https://www.passivecomponent.com/wp-content/uploads/datasheet/WTC_MLCC_General_Purpose.pdf"
			(at 0 0 0)
			(layer "F.Fab")
			(hide yes)
			(effects
				(font
					(size 1.27 1.27)
					(thickness 0.15)
				)
			)
		)
		(property "Description" "SMT Multilayer Ceramic Capacitor, 0.1 µF, 6.3 V, 0402 [1005 Metric], ± 10%, X5R, Walsin MLCC"
			(at 0 0 0)
			(layer "F.Fab")
			(hide yes)
			(effects
				(font
					(size 1.27 1.27)
					(thickness 0.15)
				)
			)
		)
		(property "Author" "Antmicro"
			(at 0 0 0)
			(layer "B.Fab")
			(hide yes)
			(effects
				(font
					(size 1 1)
					(thickness 0.15)
				)
				(justify mirror)
			)
		)
		(property "Dielectric" ""
			(at 0 0 0)
			(layer "B.Fab")
			(hide yes)
			(effects
				(font
					(size 1 1)
					(thickness 0.15)
				)
				(justify mirror)
			)
		)
		(property "License" "Apache-2.0"
			(at 0 0 0)
			(layer "B.Fab")
			(hide yes)
			(effects
				(font
					(size 1 1)
					(thickness 0.15)
				)
				(justify mirror)
			)
		)
		(property "MPN" "0402X104K6R3CT"
			(at 0 0 0)
			(layer "B.Fab")
			(hide yes)
			(effects
				(font
					(size 1 1)
					(thickness 0.15)
				)
				(justify mirror)
			)
		)
		(property "Manufacturer" "Walsin"
			(at 0 0 0)
			(layer "B.Fab")
			(hide yes)
			(effects
				(font
					(size 1 1)
					(thickness 0.15)
				)
				(justify mirror)
			)
		)
		(property "Public" "False"
			(at 0 0 0)
			(layer "B.Fab")
			(hide yes)
			(effects
				(font
					(size 1 1)
					(thickness 0.15)
				)
				(justify mirror)
			)
		)
		(property "Val" "100n"
			(at 0 0 0)
			(layer "B.Fab")
			(hide yes)
			(effects
				(font
					(size 1 1)
					(thickness 0.15)
				)
				(justify mirror)
			)
		)
		(property "Voltage" ""
			(at 0 0 0)
			(layer "B.Fab")
			(hide yes)
			(effects
				(font
					(size 1 1)
					(thickness 0.15)
				)
				(justify mirror)
			)
		)
		(sheetname "/Interfaces/")
		(sheetfile "interfaces.kicad_sch")
		(attr smd)
		(fp_rect
			(start -0.925 0.47)
			(end 0.925 -0.47)
			(stroke
				(width 0.05)
				(type default)
			)
			(fill no)
			(layer "B.CrtYd")
		)
		(fp_line
			(start -0.494 -0.248)
			(end -0.494 0.25)
			(stroke
				(width 0.15)
				(type solid)
			)
			(layer "B.Fab")
		)
		(fp_line
			(start -0.494 0.25)
			(end 0.504 0.25)
			(stroke
				(width 0.15)
				(type solid)
			)
			(layer "B.Fab")
		)
		(fp_line
			(start 0.504 -0.248)
			(end -0.494 -0.248)
			(stroke
				(width 0.15)
				(type solid)
			)
			(layer "B.Fab")
		)
		(fp_line
			(start 0.504 0.25)
			(end 0.504 -0.248)
			(stroke
				(width 0.15)
				(type solid)
			)
			(layer "B.Fab")
		)
		(pad "1" smd roundrect
			(at -0.48 0)
			(size 0.59 0.64)
			(layers "B.Cu" "B.Mask" "B.Paste")
			(roundrect_rratio 0.25)
			(net 1 "GND")
			(pintype "passive")
		)
		(pad "2" smd roundrect
			(at 0.48 0)
			(size 0.59 0.64)
			(layers "B.Cu" "B.Mask" "B.Paste")
			(roundrect_rratio 0.25)
			(net 339 "VCC1V2")
			(pintype "passive")
		)
	)
	(footprint "antmicro-footprints:C_0201"
		(layer "B.Cu")
		(at 99.225 123.675 180)
		(descr "Capacitor SMD 0201")
		(tags "capacitor SMD 0201")
		(property "Reference" "C153"
			(at -1.075 0.375 0)
			(layer "B.SilkS")
			(effects
				(font
					(size 0.7 0.7)
					(thickness 0.15)
				)
				(justify left bottom mirror)
			)
		)
		(property "Value" "C_470n_0201"
			(at 0 -1.4 0)
			(layer "B.Fab")
			(effects
				(font
					(size 0.7 0.7)
					(thickness 0.15)
				)
				(justify left bottom mirror)
			)
		)
		(property "Datasheet" "https://product.tdk.com/en/search/capacitor/ceramic/mlcc/info?part_no=C0603X5R1A474M030BC"
			(at 0 0 180)
			(layer "F.Fab")
			(hide yes)
			(effects
				(font
					(size 1.27 1.27)
					(thickness 0.15)
				)
			)
		)
		(property "Description" "SMD Multilayer Ceramic Capacitor, 0.47 µF, 10 V, 0201 [0603 Metric], ± 20%, X5R, C"
			(at 0 0 180)
			(layer "F.Fab")
			(hide yes)
			(effects
				(font
					(size 1.27 1.27)
					(thickness 0.15)
				)
			)
		)
		(property "Author" "Antmicro"
			(at 198.45 247.35 0)
			(layer "B.Fab")
			(hide yes)
			(effects
				(font
					(size 1 1)
					(thickness 0.15)
				)
				(justify mirror)
			)
		)
		(property "Dielectric" ""
			(at 198.45 247.35 0)
			(layer "B.Fab")
			(hide yes)
			(effects
				(font
					(size 1 1)
					(thickness 0.15)
				)
				(justify mirror)
			)
		)
		(property "License" "Apache-2.0"
			(at 198.45 247.35 0)
			(layer "B.Fab")
			(hide yes)
			(effects
				(font
					(size 1 1)
					(thickness 0.15)
				)
				(justify mirror)
			)
		)
		(property "MPN" "C0603X5R1A474M030BC"
			(at 198.45 247.35 0)
			(layer "B.Fab")
			(hide yes)
			(effects
				(font
					(size 1 1)
					(thickness 0.15)
				)
				(justify mirror)
			)
		)
		(property "Manufacturer" "TDK"
			(at 198.45 247.35 0)
			(layer "B.Fab")
			(hide yes)
			(effects
				(font
					(size 1 1)
					(thickness 0.15)
				)
				(justify mirror)
			)
		)
		(property "Public" "False"
			(at 198.45 247.35 0)
			(layer "B.Fab")
			(hide yes)
			(effects
				(font
					(size 1 1)
					(thickness 0.15)
				)
				(justify mirror)
			)
		)
		(property "Val" "470n"
			(at 198.45 247.35 0)
			(layer "B.Fab")
			(hide yes)
			(effects
				(font
					(size 1 1)
					(thickness 0.15)
				)
				(justify mirror)
			)
		)
		(property "Voltage" ""
			(at 198.45 247.35 0)
			(layer "B.Fab")
			(hide yes)
			(effects
				(font
					(size 1 1)
					(thickness 0.15)
				)
				(justify mirror)
			)
		)
		(property "DNP" ""
			(at 0 0 180)
			(unlocked yes)
			(layer "B.Fab")
			(hide yes)
			(effects
				(font
					(size 1 1)
					(thickness 0.15)
				)
				(justify mirror)
			)
		)
		(sheetname "/FPGA power supply/")
		(sheetfile "fpga-power-supply.kicad_sch")
		(attr smd)
		(fp_rect
			(start -0.7 0.35)
			(end 0.7 -0.35)
			(stroke
				(width 0.05)
				(type default)
			)
			(fill no)
			(layer "B.CrtYd")
		)
		(fp_rect
			(start 0.3 -0.15)
			(end -0.301 0.149)
			(stroke
				(width 0.15)
				(type solid)
			)
			(fill no)
			(layer "B.Fab")
		)
		(pad "" smd roundrect
			(at -0.349 0.002 180)
			(size 0.318 0.36)
			(layers "B.Paste")
			(roundrect_rratio 0.25)
		)
		(pad "" smd roundrect
			(at 0.341 0.002 180)
			(size 0.318 0.36)
			(layers "B.Paste")
			(roundrect_rratio 0.25)
		)
		(pad "1" smd roundrect
			(at -0.321 0.002 180)
			(size 0.46 0.4)
			(layers "B.Cu" "B.Mask")
			(roundrect_rratio 0.25)
			(net 1 "GND")
			(pintype "passive")
		)
		(pad "2" smd roundrect
			(at 0.32 0.002 180)
			(size 0.46 0.4)
			(layers "B.Cu" "B.Mask")
			(roundrect_rratio 0.25)
			(net 6 "VCC1V0")
			(pintype "passive")
		)
	)
	(footprint "antmicro-footprints:C_0402_1005Metric"
		(layer "B.Cu")
		(at 97.369 90.777 -90)
		(descr "Capacitor SMD 0402")
		(tags "capacitor SMD 0402")
		(property "Reference" "C215"
			(at -3.68 1.519 90)
			(layer "B.SilkS")
			(effects
				(font
					(size 0.7 0.7)
					(thickness 0.15)
				)
				(justify left bottom mirror)
			)
		)
		(property "Value" "C_10n_0402"
			(at 0 -1.4 90)
			(layer "B.Fab")
			(effects
				(font
					(size 0.7 0.7)
					(thickness 0.15)
				)
				(justify left bottom mirror)
			)
		)
		(property "Datasheet" "https://www.murata.com/products/productdetail?partno=GRM155R71H103KA88%23"
			(at 0 0 270)
			(layer "F.Fab")
			(hide yes)
			(effects
				(font
					(size 1.27 1.27)
					(thickness 0.15)
				)
			)
		)
		(property "Description" "SMD Multilayer Ceramic Capacitor, 10000 pF, 50 V, 0402 [1005 Metric], ± 10%, X7R, GRM Series"
			(at 0 0 270)
			(layer "F.Fab")
			(hide yes)
			(effects
				(font
					(size 1.27 1.27)
					(thickness 0.15)
				)
			)
		)
		(property "Author" "Antmicro"
			(at 6.592 188.146 0)
			(layer "B.Fab")
			(hide yes)
			(effects
				(font
					(size 1 1)
					(thickness 0.15)
				)
				(justify mirror)
			)
		)
		(property "Dielectric" "X7R"
			(at 6.592 188.146 0)
			(layer "B.Fab")
			(hide yes)
			(effects
				(font
					(size 1 1)
					(thickness 0.15)
				)
				(justify mirror)
			)
		)
		(property "License" "Apache-2.0"
			(at 6.592 188.146 0)
			(layer "B.Fab")
			(hide yes)
			(effects
				(font
					(size 1 1)
					(thickness 0.15)
				)
				(justify mirror)
			)
		)
		(property "MPN" "GRM155R71H103KA88D"
			(at 6.592 188.146 0)
			(layer "B.Fab")
			(hide yes)
			(effects
				(font
					(size 1 1)
					(thickness 0.15)
				)
				(justify mirror)
			)
		)
		(property "Manufacturer" "Murata"
			(at 6.592 188.146 0)
			(layer "B.Fab")
			(hide yes)
			(effects
				(font
					(size 1 1)
					(thickness 0.15)
				)
				(justify mirror)
			)
		)
		(property "Val" "10n"
			(at 6.592 188.146 0)
			(layer "B.Fab")
			(hide yes)
			(effects
				(font
					(size 1 1)
					(thickness 0.15)
				)
				(justify mirror)
			)
		)
		(property "Voltage" "50V"
			(at 6.592 188.146 0)
			(layer "B.Fab")
			(hide yes)
			(effects
				(font
					(size 1 1)
					(thickness 0.15)
				)
				(justify mirror)
			)
		)
		(sheetname "/Ethernet/")
		(sheetfile "ethernet.kicad_sch")
		(attr smd)
		(fp_rect
			(start -0.925 0.47)
			(end 0.925 -0.47)
			(stroke
				(width 0.05)
				(type default)
			)
			(fill no)
			(layer "B.CrtYd")
		)
		(fp_line
			(start -0.494 0.25)
			(end 0.504 0.25)
			(stroke
				(width 0.15)
				(type solid)
			)
			(layer "B.Fab")
		)
		(fp_line
			(start 0.504 0.25)
			(end 0.504 -0.248)
			(stroke
				(width 0.15)
				(type solid)
			)
			(layer "B.Fab")
		)
		(fp_line
			(start -0.494 -0.248)
			(end -0.494 0.25)
			(stroke
				(width 0.15)
				(type solid)
			)
			(layer "B.Fab")
		)
		(fp_line
			(start 0.504 -0.248)
			(end -0.494 -0.248)
			(stroke
				(width 0.15)
				(type solid)
			)
			(layer "B.Fab")
		)
		(pad "1" smd roundrect
			(at -0.48 0 270)
			(size 0.59 0.64)
			(layers "B.Cu" "B.Mask" "B.Paste")
			(roundrect_rratio 0.25)
			(net 1 "GND")
			(pintype "passive")
		)
		(pad "2" smd roundrect
			(at 0.48 0 270)
			(size 0.59 0.64)
			(layers "B.Cu" "B.Mask" "B.Paste")
			(roundrect_rratio 0.25)
			(net 406 "/Ethernet/AVDDH")
			(pintype "passive")
		)
	)
	(footprint "antmicro-footprints:C_0402_1005Metric"
		(layer "B.Cu")
		(at 96.69 94.06)
		(descr "Capacitor SMD 0402")
		(tags "capacitor SMD 0402")
		(property "Reference" "C197"
			(at -9.2 0.2 0)
			(layer "B.SilkS")
			(effects
				(font
					(size 0.7 0.7)
					(thickness 0.15)
				)
				(justify right bottom mirror)
			)
		)
		(property "Value" "C_470n_0402"
			(at 0 -1.4 0)
			(layer "B.Fab")
			(effects
				(font
					(size 0.7 0.7)
					(thickness 0.15)
				)
				(justify right bottom mirror)
			)
		)
		(property "Datasheet" "https://product.tdk.com/en/search/capacitor/ceramic/mlcc/info?part_no=C1005X5R1E474M050BB"
			(at 0 0 0)
			(layer "F.Fab")
			(hide yes)
			(effects
				(font
					(size 1.27 1.27)
					(thickness 0.15)
				)
			)
		)
		(property "Description" "SMD Multilayer Ceramic Capacitor, 0.47 µF, 25 V, 0402 [1005 Metric], ± 20%, X5R, C"
			(at 0 0 0)
			(layer "F.Fab")
			(hide yes)
			(effects
				(font
					(size 1.27 1.27)
					(thickness 0.15)
				)
			)
		)
		(property "Author" "Antmicro"
			(at 0 0 0)
			(layer "B.Fab")
			(hide yes)
			(effects
				(font
					(size 1 1)
					(thickness 0.15)
				)
				(justify mirror)
			)
		)
		(property "Dielectric" ""
			(at 0 0 0)
			(layer "B.Fab")
			(hide yes)
			(effects
				(font
					(size 1 1)
					(thickness 0.15)
				)
				(justify mirror)
			)
		)
		(property "License" "Apache-2.0"
			(at 0 0 0)
			(layer "B.Fab")
			(hide yes)
			(effects
				(font
					(size 1 1)
					(thickness 0.15)
				)
				(justify mirror)
			)
		)
		(property "MPN" "C1005X5R1E474M050BB"
			(at 0 0 0)
			(layer "B.Fab")
			(hide yes)
			(effects
				(font
					(size 1 1)
					(thickness 0.15)
				)
				(justify mirror)
			)
		)
		(property "Manufacturer" "TDK"
			(at 0 0 0)
			(layer "B.Fab")
			(hide yes)
			(effects
				(font
					(size 1 1)
					(thickness 0.15)
				)
				(justify mirror)
			)
		)
		(property "Val" "470n"
			(at 0 0 0)
			(layer "B.Fab")
			(hide yes)
			(effects
				(font
					(size 1 1)
					(thickness 0.15)
				)
				(justify mirror)
			)
		)
		(property "Voltage" ""
			(at 0 0 0)
			(layer "B.Fab")
			(hide yes)
			(effects
				(font
					(size 1 1)
					(thickness 0.15)
				)
				(justify mirror)
			)
		)
		(sheetname "/Ethernet/")
		(sheetfile "ethernet.kicad_sch")
		(attr smd)
		(fp_rect
			(start -0.925 0.47)
			(end 0.925 -0.47)
			(stroke
				(width 0.05)
				(type default)
			)
			(fill no)
			(layer "B.CrtYd")
		)
		(fp_line
			(start -0.494 -0.248)
			(end -0.494 0.25)
			(stroke
				(width 0.15)
				(type solid)
			)
			(layer "B.Fab")
		)
		(fp_line
			(start -0.494 0.25)
			(end 0.504 0.25)
			(stroke
				(width 0.15)
				(type solid)
			)
			(layer "B.Fab")
		)
		(fp_line
			(start 0.504 -0.248)
			(end -0.494 -0.248)
			(stroke
				(width 0.15)
				(type solid)
			)
			(layer "B.Fab")
		)
		(fp_line
			(start 0.504 0.25)
			(end 0.504 -0.248)
			(stroke
				(width 0.15)
				(type solid)
			)
			(layer "B.Fab")
		)
		(pad "1" smd roundrect
			(at -0.48 0)
			(size 0.59 0.64)
			(layers "B.Cu" "B.Mask" "B.Paste")
			(roundrect_rratio 0.25)
			(net 1 "GND")
			(pintype "passive")
		)
		(pad "2" smd roundrect
			(at 0.48 0)
			(size 0.59 0.64)
			(layers "B.Cu" "B.Mask" "B.Paste")
			(roundrect_rratio 0.25)
			(net 339 "VCC1V2")
			(pintype "passive")
		)
	)
)
